(kicad_pcb
	(version 20260206)
	(generator "pcbnew")
	(generator_version "10.0")
	(general
		(thickness 1.6)
		(legacy_teardrops no)
	)
	(paper "A4")
	(title_block
		(title "Bryce Canyon_IOM_IOC_16318-2_OCP.brd")
		(comment 1 "Bryce Canyon / footprints 1537-1545 of 1605")
	)
	(layers
		(0 "F.Cu" signal "TOP")
		(4 "In1.Cu" signal "L2GND")
		(6 "In2.Cu" signal "L3")
		(8 "In3.Cu" signal "L4VCC")
		(10 "In4.Cu" signal "L5VCC")
		(12 "In5.Cu" signal "L6")
		(14 "In6.Cu" signal "L7GND")
		(2 "B.Cu" signal "BOTTOM")
		(9 "F.Adhes" user "F.Adhesive")
		(11 "B.Adhes" user "B.Adhesive")
		(13 "F.Paste" user "Package Geometry/Pastemask Top")
		(15 "B.Paste" user "Package Geometry/Pastemask Bottom")
		(5 "F.SilkS" user "Ref Des/Silkscreen Top")
		(7 "B.SilkS" user "Ref Des/Silkscreen Bottom")
		(1 "F.Mask" user "Board Geometry/Soldermask Top")
		(3 "B.Mask" user "Board Geometry/Soldermask Bottom")
		(17 "Dwgs.User" user "User.Drawings")
		(19 "Cmts.User" user "User.Comments")
		(21 "Eco1.User" user "User.Eco1")
		(23 "Eco2.User" user "User.Eco2")
		(25 "Edge.Cuts" user "Board Geometry/Outline")
		(27 "Margin" user)
		(31 "F.CrtYd" user "Package Geometry/Place Bound Top")
		(29 "B.CrtYd" user "Package Geometry/Place Bound Bottom")
		(35 "F.Fab" user "Ref Des/Assembly Top")
		(33 "B.Fab" user "Ref Des/Assembly Bottom")
	)
	(footprint ""
		(layer "B.Cu")
		(at 32.713168 -153.124916 90)
		(property "Reference" "R336"
			(at 0 0 90)
			(layer "B.SilkS")
			(hide yes)
			(effects
				(font
					(size 1.27 1.27)
				)
				(justify mirror)
			)
		)
		(property "Value" "4K7R2F-GP"
			(at -0.064008 -3.993896 90)
			(unlocked yes)
			(layer "B.Fab")
			(hide yes)
			(effects
				(font
					(size 1.016 1.016)
					(thickness 0.1524)
				)
				(justify mirror)
			)
		)
		(property "Device Type" "R402H16"
			(at -0.064008 -5.517896 90)
			(unlocked yes)
			(layer "B.Fab")
			(hide yes)
			(effects
				(font
					(size 1.016 1.016)
					(thickness 0.1524)
				)
				(justify mirror)
			)
		)
		(duplicate_pad_numbers_are_jumpers no)
		(fp_line
			(start 0.508 -0.9398)
			(end 0.508 0.9398)
			(stroke
				(width 0.1524)
				(type default)
			)
			(layer "B.SilkS")
		)
		(fp_line
			(start -0.508 -0.9398)
			(end 0.508 -0.9398)
			(stroke
				(width 0.1524)
				(type default)
			)
			(layer "B.SilkS")
		)
		(fp_rect
			(start 0.508 0.9398)
			(end -0.508 -0.9398)
			(stroke
				(width 0)
				(type default)
			)
			(fill no)
			(layer "B.CrtYd")
		)
		(fp_rect
			(start 0.508 0.9398)
			(end -0.508 -0.9398)
			(stroke
				(width 0)
				(type default)
			)
			(fill no)
			(layer "B.Fab")
		)
		(pad "1" smd custom
			(at 0 -0.4445 270)
			(size 0.1397 0.1397)
			(layers "B.Cu" "B.Mask" "B.Paste")
			(net "P3V3_STBY")
			(options
				(clearance outline)
				(anchor circle)
			)
			(primitives
				(gr_poly
					(pts
						(arc
							(start -0.1778 0.2794)
							(mid -0.249642 0.249642)
							(end -0.2794 0.1778)
						)
						(arc
							(start -0.2794 -0.1778)
							(mid -0.249642 -0.249642)
							(end -0.1778 -0.2794)
						)
						(arc
							(start 0.1778 -0.2794)
							(mid 0.249642 -0.249642)
							(end 0.2794 -0.1778)
						)
						(arc
							(start 0.2794 0.1778)
							(mid 0.249642 0.249642)
							(end 0.1778 0.2794)
						)
					)
					(width 0)
					(fill yes)
				)
			)
		)
		(pad "2" smd custom
			(at 0 0.4445 270)
			(size 0.1397 0.1397)
			(layers "B.Cu" "B.Mask" "B.Paste")
			(net "ENCL_FAULT_LED")
			(options
				(clearance outline)
				(anchor circle)
			)
			(primitives
				(gr_poly
					(pts
						(arc
							(start -0.1778 0.2794)
							(mid -0.249642 0.249642)
							(end -0.2794 0.1778)
						)
						(arc
							(start -0.2794 -0.1778)
							(mid -0.249642 -0.249642)
							(end -0.1778 -0.2794)
						)
						(arc
							(start 0.1778 -0.2794)
							(mid 0.249642 -0.249642)
							(end 0.2794 -0.1778)
						)
						(arc
							(start 0.2794 0.1778)
							(mid 0.249642 0.249642)
							(end 0.1778 0.2794)
						)
					)
					(width 0)
					(fill yes)
				)
			)
		)
	)
	(footprint ""
		(layer "B.Cu")
		(at 52.1716 -162.88258 90)
		(property "Reference" "R408"
			(at 0 0 90)
			(layer "B.SilkS")
			(hide yes)
			(effects
				(font
					(size 1.27 1.27)
				)
				(justify mirror)
			)
		)
		(property "Value" "1KR2F-3-GP"
			(at -0.064008 -3.993896 90)
			(unlocked yes)
			(layer "B.Fab")
			(hide yes)
			(effects
				(font
					(size 1.016 1.016)
					(thickness 0.1524)
				)
				(justify mirror)
			)
		)
		(property "Device Type" "R402H16"
			(at -0.064008 -5.517896 90)
			(unlocked yes)
			(layer "B.Fab")
			(hide yes)
			(effects
				(font
					(size 1.016 1.016)
					(thickness 0.1524)
				)
				(justify mirror)
			)
		)
		(duplicate_pad_numbers_are_jumpers no)
		(fp_line
			(start 0.508 -0.9398)
			(end 0.508 0.9398)
			(stroke
				(width 0.1524)
				(type default)
			)
			(layer "B.SilkS")
		)
		(fp_line
			(start -0.508 -0.9398)
			(end 0.508 -0.9398)
			(stroke
				(width 0.1524)
				(type default)
			)
			(layer "B.SilkS")
		)
		(fp_rect
			(start 0.508 0.9398)
			(end -0.508 -0.9398)
			(stroke
				(width 0)
				(type default)
			)
			(fill no)
			(layer "B.CrtYd")
		)
		(fp_rect
			(start 0.508 0.9398)
			(end -0.508 -0.9398)
			(stroke
				(width 0)
				(type default)
			)
			(fill no)
			(layer "B.Fab")
		)
		(pad "1" smd custom
			(at 0 -0.4445 270)
			(size 0.1397 0.1397)
			(layers "B.Cu" "B.Mask" "B.Paste")
			(net "P1V5")
			(options
				(clearance outline)
				(anchor circle)
			)
			(primitives
				(gr_poly
					(pts
						(arc
							(start -0.1778 0.2794)
							(mid -0.249642 0.249642)
							(end -0.2794 0.1778)
						)
						(arc
							(start -0.2794 -0.1778)
							(mid -0.249642 -0.249642)
							(end -0.1778 -0.2794)
						)
						(arc
							(start 0.1778 -0.2794)
							(mid 0.249642 -0.249642)
							(end 0.2794 -0.1778)
						)
						(arc
							(start 0.2794 0.1778)
							(mid 0.249642 0.249642)
							(end 0.1778 0.2794)
						)
					)
					(width 0)
					(fill yes)
				)
			)
		)
		(pad "2" smd custom
			(at 0 0.4445 270)
			(size 0.1397 0.1397)
			(layers "B.Cu" "B.Mask" "B.Paste")
			(net "ADC_P1V5")
			(options
				(clearance outline)
				(anchor circle)
			)
			(primitives
				(gr_poly
					(pts
						(arc
							(start -0.1778 0.2794)
							(mid -0.249642 0.249642)
							(end -0.2794 0.1778)
						)
						(arc
							(start -0.2794 -0.1778)
							(mid -0.249642 -0.249642)
							(end -0.1778 -0.2794)
						)
						(arc
							(start 0.1778 -0.2794)
							(mid 0.249642 -0.249642)
							(end 0.2794 -0.1778)
						)
						(arc
							(start 0.2794 0.1778)
							(mid 0.249642 0.249642)
							(end 0.1778 0.2794)
						)
					)
					(width 0)
					(fill yes)
				)
			)
		)
	)
	(footprint ""
		(layer "B.Cu")
		(at 55.74919 -147.916392)
		(property "Reference" "TP82"
			(at 0 0 0)
			(layer "B.SilkS")
			(hide yes)
			(effects
				(font
					(size 1.27 1.27)
				)
				(justify mirror)
			)
		)
		(property "Value" "TPAD28-2-GP"
			(at 0.0127 -1.6637 0)
			(unlocked yes)
			(layer "B.Fab")
			(hide yes)
			(effects
				(font
					(size 1.016 1.016)
					(thickness 0.1524)
				)
				(justify mirror)
			)
		)
		(property "Device Type" "TPAD28"
			(at 0.0127 -3.1877 0)
			(unlocked yes)
			(layer "B.Fab")
			(hide yes)
			(effects
				(font
					(size 1.016 1.016)
					(thickness 0.1524)
				)
				(justify mirror)
			)
		)
		(duplicate_pad_numbers_are_jumpers no)
		(fp_poly
			(pts
				(arc
					(start 0.3556 0)
					(mid -0.3556 0)
					(end 0.3556 0)
				)
			)
			(stroke
				(width 0)
				(type default)
			)
			(fill no)
			(layer "B.CrtYd")
		)
		(fp_poly
			(pts
				(arc
					(start 0.6096 0)
					(mid -0.6096 0)
					(end 0.6096 0)
				)
			)
			(stroke
				(width 0)
				(type default)
			)
			(fill no)
			(layer "B.Fab")
		)
		(pad "1" smd circle
			(at 0 0 180)
			(size 0.7112 0.7112)
			(layers "B.Cu" "B.Mask" "B.Paste")
			(net "BMC0_JTAG_RTCK")
		)
	)
	(footprint ""
		(layer "B.Cu")
		(at 202.9968 -54.9529)
		(property "Reference" "C437"
			(at 0 0 0)
			(layer "B.SilkS")
			(hide yes)
			(effects
				(font
					(size 1.27 1.27)
				)
				(justify mirror)
			)
		)
		(property "Value" "SCD1U16V2KX-3GP"
			(at -1.1811 -2.7051 0)
			(unlocked yes)
			(layer "B.Fab")
			(hide yes)
			(effects
				(font
					(size 1.016 1.016)
					(thickness 0.1524)
				)
				(justify mirror)
			)
		)
		(property "Device Type" "C402H22"
			(at -1.1811 -4.2291 0)
			(unlocked yes)
			(layer "B.Fab")
			(hide yes)
			(effects
				(font
					(size 1.016 1.016)
					(thickness 0.1524)
				)
				(justify mirror)
			)
		)
		(duplicate_pad_numbers_are_jumpers no)
		(fp_rect
			(start 0.4318 0.9525)
			(end -0.4318 -0.9525)
			(stroke
				(width 0)
				(type default)
			)
			(fill no)
			(layer "B.CrtYd")
		)
		(fp_rect
			(start 0.4318 0.9525)
			(end -0.4318 -0.9525)
			(stroke
				(width 0)
				(type default)
			)
			(fill no)
			(layer "B.Fab")
		)
		(pad "1" smd custom
			(at 0 -0.4445 180)
			(size 0.1524 0.1524)
			(layers "B.Cu" "B.Mask" "B.Paste")
			(net "P1V8")
			(options
				(clearance outline)
				(anchor circle)
			)
			(primitives
				(gr_poly
					(pts
						(arc
							(start 0.3048 0.2032)
							(mid 0.275042 0.275042)
							(end 0.2032 0.3048)
						)
						(arc
							(start -0.2032 0.3048)
							(mid -0.275042 0.275042)
							(end -0.3048 0.2032)
						)
						(arc
							(start -0.3048 -0.2032)
							(mid -0.275042 -0.275042)
							(end -0.2032 -0.3048)
						)
						(arc
							(start 0.2032 -0.3048)
							(mid 0.275042 -0.275042)
							(end 0.3048 -0.2032)
						)
					)
					(width 0)
					(fill yes)
				)
			)
		)
		(pad "2" smd custom
			(at 0 0.4445 180)
			(size 0.1524 0.1524)
			(layers "B.Cu" "B.Mask" "B.Paste")
			(net "GND")
			(options
				(clearance outline)
				(anchor circle)
			)
			(primitives
				(gr_poly
					(pts
						(arc
							(start 0.3048 0.2032)
							(mid 0.275042 0.275042)
							(end 0.2032 0.3048)
						)
						(arc
							(start -0.2032 0.3048)
							(mid -0.275042 0.275042)
							(end -0.3048 0.2032)
						)
						(arc
							(start -0.3048 -0.2032)
							(mid -0.275042 -0.275042)
							(end -0.2032 -0.3048)
						)
						(arc
							(start 0.2032 -0.3048)
							(mid 0.275042 -0.275042)
							(end 0.3048 -0.2032)
						)
					)
					(width 0)
					(fill yes)
				)
			)
		)
	)
	(footprint ""
		(layer "B.Cu")
		(at 187.1472 -70.6882)
		(property "Reference" "TP148"
			(at 0 0 0)
			(layer "B.SilkS")
			(hide yes)
			(effects
				(font
					(size 1.27 1.27)
				)
				(justify mirror)
			)
		)
		(property "Value" "TPAD28-2-GP"
			(at 0.0127 -1.6637 0)
			(unlocked yes)
			(layer "B.Fab")
			(hide yes)
			(effects
				(font
					(size 1.016 1.016)
					(thickness 0.1524)
				)
				(justify mirror)
			)
		)
		(property "Device Type" "TPAD28"
			(at 0.0127 -3.1877 0)
			(unlocked yes)
			(layer "B.Fab")
			(hide yes)
			(effects
				(font
					(size 1.016 1.016)
					(thickness 0.1524)
				)
				(justify mirror)
			)
		)
		(duplicate_pad_numbers_are_jumpers no)
		(fp_poly
			(pts
				(arc
					(start 0.3556 0)
					(mid -0.3556 0)
					(end 0.3556 0)
				)
			)
			(stroke
				(width 0)
				(type default)
			)
			(fill no)
			(layer "B.CrtYd")
		)
		(fp_poly
			(pts
				(arc
					(start 0.6096 0)
					(mid -0.6096 0)
					(end 0.6096 0)
				)
			)
			(stroke
				(width 0)
				(type default)
			)
			(fill no)
			(layer "B.Fab")
		)
		(pad "1" smd circle
			(at 0 0 180)
			(size 0.7112 0.7112)
			(layers "B.Cu" "B.Mask" "B.Paste")
			(net "SYS_DBMODE0")
		)
	)
	(footprint ""
		(layer "B.Cu")
		(at 195.193666 -53.457856)
		(property "Reference" "C459"
			(at 0 0 0)
			(layer "B.SilkS")
			(hide yes)
			(effects
				(font
					(size 1.27 1.27)
				)
				(justify mirror)
			)
		)
		(property "Value" "SCD1U16V2KX-3GP"
			(at -1.1811 -2.7051 0)
			(unlocked yes)
			(layer "B.Fab")
			(hide yes)
			(effects
				(font
					(size 1.016 1.016)
					(thickness 0.1524)
				)
				(justify mirror)
			)
		)
		(property "Device Type" "C402H22"
			(at -1.1811 -4.2291 0)
			(unlocked yes)
			(layer "B.Fab")
			(hide yes)
			(effects
				(font
					(size 1.016 1.016)
					(thickness 0.1524)
				)
				(justify mirror)
			)
		)
		(duplicate_pad_numbers_are_jumpers no)
		(fp_rect
			(start 0.4318 0.9525)
			(end -0.4318 -0.9525)
			(stroke
				(width 0)
				(type default)
			)
			(fill no)
			(layer "B.CrtYd")
		)
		(fp_rect
			(start 0.4318 0.9525)
			(end -0.4318 -0.9525)
			(stroke
				(width 0)
				(type default)
			)
			(fill no)
			(layer "B.Fab")
		)
		(pad "1" smd custom
			(at 0 -0.4445 180)
			(size 0.1524 0.1524)
			(layers "B.Cu" "B.Mask" "B.Paste")
			(net "P1V8")
			(options
				(clearance outline)
				(anchor circle)
			)
			(primitives
				(gr_poly
					(pts
						(arc
							(start 0.3048 0.2032)
							(mid 0.275042 0.275042)
							(end 0.2032 0.3048)
						)
						(arc
							(start -0.2032 0.3048)
							(mid -0.275042 0.275042)
							(end -0.3048 0.2032)
						)
						(arc
							(start -0.3048 -0.2032)
							(mid -0.275042 -0.275042)
							(end -0.2032 -0.3048)
						)
						(arc
							(start 0.2032 -0.3048)
							(mid 0.275042 -0.275042)
							(end 0.3048 -0.2032)
						)
					)
					(width 0)
					(fill yes)
				)
			)
		)
		(pad "2" smd custom
			(at 0 0.4445 180)
			(size 0.1524 0.1524)
			(layers "B.Cu" "B.Mask" "B.Paste")
			(net "GND")
			(options
				(clearance outline)
				(anchor circle)
			)
			(primitives
				(gr_poly
					(pts
						(arc
							(start 0.3048 0.2032)
							(mid 0.275042 0.275042)
							(end 0.2032 0.3048)
						)
						(arc
							(start -0.2032 0.3048)
							(mid -0.275042 0.275042)
							(end -0.3048 0.2032)
						)
						(arc
							(start -0.3048 -0.2032)
							(mid -0.275042 -0.275042)
							(end -0.2032 -0.3048)
						)
						(arc
							(start 0.2032 -0.3048)
							(mid 0.275042 -0.275042)
							(end 0.3048 -0.2032)
						)
					)
					(width 0)
					(fill yes)
				)
			)
		)
	)
	(footprint ""
		(layer "B.Cu")
		(at 194.2846 -53.848)
		(property "Reference" "C434"
			(at 0 0 0)
			(layer "B.SilkS")
			(hide yes)
			(effects
				(font
					(size 1.27 1.27)
				)
				(justify mirror)
			)
		)
		(property "Value" "SCD1U16V2KX-3GP"
			(at -1.1811 -2.7051 0)
			(unlocked yes)
			(layer "B.Fab")
			(hide yes)
			(effects
				(font
					(size 1.016 1.016)
					(thickness 0.1524)
				)
				(justify mirror)
			)
		)
		(property "Device Type" "C402H22"
			(at -1.1811 -4.2291 0)
			(unlocked yes)
			(layer "B.Fab")
			(hide yes)
			(effects
				(font
					(size 1.016 1.016)
					(thickness 0.1524)
				)
				(justify mirror)
			)
		)
		(duplicate_pad_numbers_are_jumpers no)
		(fp_rect
			(start 0.4318 0.9525)
			(end -0.4318 -0.9525)
			(stroke
				(width 0)
				(type default)
			)
			(fill no)
			(layer "B.CrtYd")
		)
		(fp_rect
			(start 0.4318 0.9525)
			(end -0.4318 -0.9525)
			(stroke
				(width 0)
				(type default)
			)
			(fill no)
			(layer "B.Fab")
		)
		(pad "1" smd custom
			(at 0 -0.4445 180)
			(size 0.1524 0.1524)
			(layers "B.Cu" "B.Mask" "B.Paste")
			(net "P1V8")
			(options
				(clearance outline)
				(anchor circle)
			)
			(primitives
				(gr_poly
					(pts
						(arc
							(start 0.3048 0.2032)
							(mid 0.275042 0.275042)
							(end 0.2032 0.3048)
						)
						(arc
							(start -0.2032 0.3048)
							(mid -0.275042 0.275042)
							(end -0.3048 0.2032)
						)
						(arc
							(start -0.3048 -0.2032)
							(mid -0.275042 -0.275042)
							(end -0.2032 -0.3048)
						)
						(arc
							(start 0.2032 -0.3048)
							(mid 0.275042 -0.275042)
							(end 0.3048 -0.2032)
						)
					)
					(width 0)
					(fill yes)
				)
			)
		)
		(pad "2" smd custom
			(at 0 0.4445 180)
			(size 0.1524 0.1524)
			(layers "B.Cu" "B.Mask" "B.Paste")
			(net "GND")
			(options
				(clearance outline)
				(anchor circle)
			)
			(primitives
				(gr_poly
					(pts
						(arc
							(start 0.3048 0.2032)
							(mid 0.275042 0.275042)
							(end 0.2032 0.3048)
						)
						(arc
							(start -0.2032 0.3048)
							(mid -0.275042 0.275042)
							(end -0.3048 0.2032)
						)
						(arc
							(start -0.3048 -0.2032)
							(mid -0.275042 -0.275042)
							(end -0.2032 -0.3048)
						)
						(arc
							(start 0.2032 -0.3048)
							(mid 0.275042 -0.275042)
							(end 0.3048 -0.2032)
						)
					)
					(width 0)
					(fill yes)
				)
			)
		)
	)
	(footprint ""
		(layer "B.Cu")
		(at 49.81321 -120.888252 90)
		(property "Reference" "R342"
			(at 0 0 90)
			(layer "B.SilkS")
			(hide yes)
			(effects
				(font
					(size 1.27 1.27)
				)
				(justify mirror)
			)
		)
		(property "Value" "0R2J-2-GP"
			(at -0.064008 -3.993896 90)
			(unlocked yes)
			(layer "B.Fab")
			(hide yes)
			(effects
				(font
					(size 1.016 1.016)
					(thickness 0.1524)
				)
				(justify mirror)
			)
		)
		(property "Device Type" "R402H16"
			(at -0.064008 -5.517896 90)
			(unlocked yes)
			(layer "B.Fab")
			(hide yes)
			(effects
				(font
					(size 1.016 1.016)
					(thickness 0.1524)
				)
				(justify mirror)
			)
		)
		(duplicate_pad_numbers_are_jumpers no)
		(fp_line
			(start 0.508 -0.9398)
			(end 0.508 0.9398)
			(stroke
				(width 0.1524)
				(type default)
			)
			(layer "B.SilkS")
		)
		(fp_line
			(start -0.508 -0.9398)
			(end 0.508 -0.9398)
			(stroke
				(width 0.1524)
				(type default)
			)
			(layer "B.SilkS")
		)
		(fp_rect
			(start 0.508 0.9398)
			(end -0.508 -0.9398)
			(stroke
				(width 0)
				(type default)
			)
			(fill no)
			(layer "B.CrtYd")
		)
		(fp_rect
			(start 0.508 0.9398)
			(end -0.508 -0.9398)
			(stroke
				(width 0)
				(type default)
			)
			(fill no)
			(layer "B.Fab")
		)
		(pad "1" smd custom
			(at 0 -0.4445 270)
			(size 0.1397 0.1397)
			(layers "B.Cu" "B.Mask" "B.Paste")
			(net "TEMP_3_SDA")
			(options
				(clearance outline)
				(anchor circle)
			)
			(primitives
				(gr_poly
					(pts
						(arc
							(start -0.1778 0.2794)
							(mid -0.249642 0.249642)
							(end -0.2794 0.1778)
						)
						(arc
							(start -0.2794 -0.1778)
							(mid -0.249642 -0.249642)
							(end -0.1778 -0.2794)
						)
						(arc
							(start 0.1778 -0.2794)
							(mid 0.249642 -0.249642)
							(end 0.2794 -0.1778)
						)
						(arc
							(start 0.2794 0.1778)
							(mid 0.249642 0.249642)
							(end 0.1778 0.2794)
						)
					)
					(width 0)
					(fill yes)
				)
			)
		)
		(pad "2" smd custom
			(at 0 0.4445 270)
			(size 0.1397 0.1397)
			(layers "B.Cu" "B.Mask" "B.Paste")
			(net "I2C_IOM_SDA")
			(options
				(clearance outline)
				(anchor circle)
			)
			(primitives
				(gr_poly
					(pts
						(arc
							(start -0.1778 0.2794)
							(mid -0.249642 0.249642)
							(end -0.2794 0.1778)
						)
						(arc
							(start -0.2794 -0.1778)
							(mid -0.249642 -0.249642)
							(end -0.1778 -0.2794)
						)
						(arc
							(start 0.1778 -0.2794)
							(mid 0.249642 -0.249642)
							(end 0.2794 -0.1778)
						)
						(arc
							(start 0.2794 0.1778)
							(mid 0.249642 0.249642)
							(end 0.1778 0.2794)
						)
					)
					(width 0)
					(fill yes)
				)
			)
		)
	)
	(footprint ""
		(layer "B.Cu")
		(at 177.28184 -74.2696)
		(property "Reference" "TP119"
			(at 0 0 0)
			(layer "B.SilkS")
			(hide yes)
			(effects
				(font
					(size 1.27 1.27)
				)
				(justify mirror)
			)
		)
		(property "Value" "TPAD28-2-GP"
			(at 0.0127 -1.6637 0)
			(unlocked yes)
			(layer "B.Fab")
			(hide yes)
			(effects
				(font
					(size 1.016 1.016)
					(thickness 0.1524)
				)
				(justify mirror)
			)
		)
		(property "Device Type" "TPAD28"
			(at 0.0127 -3.1877 0)
			(unlocked yes)
			(layer "B.Fab")
			(hide yes)
			(effects
				(font
					(size 1.016 1.016)
					(thickness 0.1524)
				)
				(justify mirror)
			)
		)
		(duplicate_pad_numbers_are_jumpers no)
		(fp_poly
			(pts
				(arc
					(start 0.3556 0)
					(mid -0.3556 0)
					(end 0.3556 0)
				)
			)
			(stroke
				(width 0)
				(type default)
			)
			(fill no)
			(layer "B.CrtYd")
		)
		(fp_poly
			(pts
				(arc
					(start 0.6096 0)
					(mid -0.6096 0)
					(end 0.6096 0)
				)
			)
			(stroke
				(width 0)
				(type default)
			)
			(fill no)
			(layer "B.Fab")
		)
		(pad "1" smd circle
			(at 0 0 180)
			(size 0.7112 0.7112)
			(layers "B.Cu" "B.Mask" "B.Paste")
			(net "IOC_GPIO_30")
		)
	)
)
